# BASEBOARD_FAB2 (Tioga Pass) — schematic netlist excerpt (pin names and nets, part order shuffled) for the footprints in the layout excerpt that follows; sources: Cadence DE-HDL packaged netlist, KiCad conversion of Wiwynn_Tioga_Pass_MB.brd

J1G3  SCONN288_H44441004  SCONN  pkg PIP  page 81
  \12v\(1)  = P12V_NVDIMM_GHJ
  VSS(93)  = GND
  DQ(4)  = M_J_DQ<5>
  VSS(92)  = GND
  DQ(0)  = M_J_DQ<1>
  VSS(91)  = GND
  DQS9P  = M_J_DQS_DP<9>
  DQS9N  = M_J_DQS_DN<9>
  VSS(90)  = GND
  DQ(6)  = M_J_DQ<7>
  VSS(89)  = GND
  DQ(2)  = M_J_DQ<3>
  VSS(88)  = GND
  DQ(12)  = M_J_DQ<13>
  VSS(87)  = GND
  DQ(8)  = M_J_DQ<9>
  VSS(86)  = GND
  DQS10P  = M_J_DQS_DP<10>
  DQS10N  = M_J_DQS_DN<10>
  VSS(85)  = GND
  DQ(14)  = M_J_DQ<15>
  VSS(84)  = GND
  DQ(10)  = M_J_DQ<11>
  VSS(83)  = GND
  DQ(20)  = M_J_DQ<21>
  VSS(82)  = GND
  DQ(16)  = M_J_DQ<17>
  VSS(81)  = GND
  DQS11P  = M_J_DQS_DP<11>
  DQS11N  = M_J_DQS_DN<11>
  VSS(80)  = GND
  DQ(22)  = M_J_DQ<23>
  VSS(79)  = GND
  DQ(18)  = M_J_DQ<19>
  VSS(78)  = GND
  DQ(28)  = M_J_DQ<29>
  VSS(77)  = GND
  DQ(24)  = M_J_DQ<25>
  VSS(76)  = GND
  DQS12P  = M_J_DQS_DP<12>
  DQS12N  = M_J_DQS_DN<12>
  VSS(75)  = GND
  DQ(30)  = M_J_DQ<31>
  VSS(74)  = GND
  DQ(26)  = M_J_DQ<27>
  VSS(73)  = GND
  CB(4)  = M_J_ECC<5>
  VSS(72)  = GND
  CB(0)  = M_J_ECC<1>
  VSS(71)  = GND
  DQS17P  = M_J_DQS_DP<17>
  DQS17N  = M_J_DQS_DN<17>
  VSS(70)  = GND
  CB(6)  = M_J_ECC<7>
  VSS(69)  = GND
  CB(2)  = M_J_ECC<3>
  VSS(68)  = GND
  RESET_N  = M_GHJ_RST_N
  VDD(25)  = PVDDQ_GHJ
  CKE(0)  = M_J_CKE<0>
  VDD(24)  = PVDDQ_GHJ
  ACT_N  = M_J_ACT_N
  BG(0)  = M_J_BG<0>
  VDD(23)  = PVDDQ_GHJ
  A12  = M_J_MA<12>
  A9  = M_J_MA<9>
  VDD(22)  = PVDDQ_GHJ
  A8  = M_J_MA<8>
  A6  = M_J_MA<6>
  VDD(21)  = PVDDQ_GHJ
  A3  = M_J_MA<3>
  A1  = M_J_MA<1>
  VDD(20)  = PVDDQ_GHJ
  CK0P  = M_J_CLK_DP<0>
  CK0N  = M_J_CLK_DN<0>
  VDD(19)  = PVDDQ_GHJ
  VTT(1)  = PVTT_GHJ
  EVENT_N  = FM_DIMM_EVENT_COD_N
  A0  = M_J_MA<0>
  VDD(18)  = PVDDQ_GHJ
  BA(0)  = M_J_BA<0>
  A16_RAS_N  = M_J_MA<16>
  VDD(17)  = PVDDQ_GHJ
  S0_N  = M_J_CS_N<0>
  VDD(16)  = PVDDQ_GHJ
  A15_CAS_N  = M_J_MA<15>
  ODT(0)  = M_J_ODT<0>
  VDD(15)  = PVDDQ_GHJ
  S1_N  = M_J_CS_N<1>
  VDD(14)  = PVDDQ_GHJ
  ODT(1)  = M_J_ODT<1>
  VDD(13)  = PVDDQ_GHJ
  S2_N_C(0)  = M_J_CS_N<2>
  VSS(67)  = GND
  DQ(36)  = M_J_DQ<37>
  VSS(66)  = GND
  DQ(32)  = M_J_DQ<33>
  VSS(65)  = GND
  DQS13P  = M_J_DQS_DP<13>
  DQS13N  = M_J_DQS_DN<13>
  VSS(64)  = GND
  DQ(38)  = M_J_DQ<39>
  VSS(63)  = GND
  DQ(34)  = M_J_DQ<35>
  VSS(62)  = GND
  DQ(44)  = M_J_DQ<45>
  VSS(61)  = GND
  DQ(40)  = M_J_DQ<41>
  VSS(60)  = GND
  DQS14P  = M_J_DQS_DP<14>
  DQS14N  = M_J_DQS_DN<14>
  VSS(59)  = GND
  DQ(46)  = M_J_DQ<47>
  VSS(58)  = GND
  DQ(42)  = M_J_DQ<43>
  VSS(57)  = GND
  DQ(52)  = M_J_DQ<53>
  VSS(56)  = GND
  DQ(48)  = M_J_DQ<49>
  VSS(55)  = GND
  DQS15P  = M_J_DQS_DP<15>
  DQS15N  = M_J_DQS_DN<15>
  VSS(54)  = GND
  DQ(54)  = M_J_DQ<55>
  VSS(53)  = GND
  DQ(50)  = M_J_DQ<51>
  VSS(52)  = GND
  DQ(60)  = M_J_DQ<61>
  VSS(51)  = GND
  DQ(56)  = M_J_DQ<57>
  VSS(50)  = GND
  DQS16P  = M_J_DQS_DP<16>
  DQS16N  = M_J_DQS_DN<16>
  VSS(49)  = GND
  DQ(62)  = M_J_DQ<63>
  VSS(48)  = GND
  DQ(58)  = M_J_DQ<59>
  VSS(47)  = GND
  SA(0)  = GND
  SA(1)  = GND
  SCL  = SMB_DDR_GHJ_VPP_SCL
  VPP(4)  = PVPP_GHJ
  VPP(3)  = PVPP_GHJ
  RFU(2)  = TP_CH_J_DIMM_J0_RFU_2
  \12v\(0)  = P12V_NVDIMM_GHJ
  VREFCA  = M_J_VREF
  VSS(46)  = GND
  DQ(5)  = M_J_DQ<4>
  VSS(45)  = GND
  DQ(1)  = M_J_DQ<0>
  VSS(44)  = GND
  DQS0N  = M_J_DQS_DN<0>
  DQS0P  = M_J_DQS_DP<0>
  VSS(43)  = GND
  DQ(7)  = M_J_DQ<6>
  VSS(42)  = GND
  DQ(3)  = M_J_DQ<2>
  VSS(41)  = GND
  DQ(13)  = M_J_DQ<12>
  VSS(40)  = GND
  DQ(9)  = M_J_DQ<8>
  VSS(39)  = GND
  DQS1N  = M_J_DQS_DN<1>
  DQS1P  = M_J_DQS_DP<1>
  VSS(38)  = GND
  DQ(15)  = M_J_DQ<14>
  VSS(37)  = GND
  DQ(11)  = M_J_DQ<10>
  VSS(36)  = GND
  DQ(21)  = M_J_DQ<20>
  VSS(35)  = GND
  DQ(17)  = M_J_DQ<16>
  VSS(34)  = GND
  DQS2N  = M_J_DQS_DN<2>
  DQS2P  = M_J_DQS_DP<2>
  VSS(33)  = GND
  DQ(23)  = M_J_DQ<22>
  VSS(32)  = GND
  DQ(19)  = M_J_DQ<18>
  VSS(31)  = GND
  DQ(29)  = M_J_DQ<28>
  VSS(30)  = GND
  DQ(25)  = M_J_DQ<24>
  VSS(29)  = GND
  DQS3N  = M_J_DQS_DN<3>
  DQS3P  = M_J_DQS_DP<3>
  VSS(28)  = GND
  DQ(31)  = M_J_DQ<30>
  VSS(27)  = GND
  DQ(27)  = M_J_DQ<26>
  VSS(26)  = GND
  CB(5)  = M_J_ECC<4>
  VSS(25)  = GND
  CB(1)  = M_J_ECC<0>
  VSS(24)  = GND
  DQS8N  = M_J_DQS_DN<8>
  DQS8P  = M_J_DQS_DP<8>
  VSS(23)  = GND
  CB(7)  = M_J_ECC<6>
  VSS(22)  = GND
  CB(3)  = M_J_ECC<2>
  VSS(21)  = GND
  CKE(1)  = M_J_CKE<1>
  VDD(12)  = PVDDQ_GHJ
  RFU(0)  = TP_CH_J_DIMM_J0_RFU_0
  VDD(11)  = PVDDQ_GHJ
  BG(1)  = M_J_BG<1>
  ALERT_N  = M_J_ALERT_N
  VDD(10)  = PVDDQ_GHJ
  A11  = M_J_MA<11>
  A7  = M_J_MA<7>
  VDD(9)  = PVDDQ_GHJ
  A5  = M_J_MA<5>
  A4  = M_J_MA<4>
  VDD(8)  = PVDDQ_GHJ
  A2  = M_J_MA<2>
  VDD(7)  = PVDDQ_GHJ
  CK1P  = M_J_CLK_DP<1>
  CK1N  = M_J_CLK_DN<1>
  VDD(6)  = PVDDQ_GHJ
  VTT(0)  = PVTT_GHJ
  PAR  = M_J_PAR
  VDD(5)  = PVDDQ_GHJ
  BA(1)  = M_J_BA<1>
  A10  = M_J_MA<10>
  VDD(4)  = PVDDQ_GHJ
  RFU(1)  = TP_CH_J_DIMM_J0_RFU_1
  A14_WE_N  = M_J_MA<14>
  VDD(3)  = PVDDQ_GHJ
  SAVE_N_NC  = FM_ADR_COMPLETE_GHJ_N
  VDD(2)  = PVDDQ_GHJ
  A13  = M_J_MA<13>
  VDD(1)  = PVDDQ_GHJ
  A17  = M_J_MA<17>
  C(2)  = M_J_C<2>
  VDD(0)  = PVDDQ_GHJ
  S3_N_C(1)  = M_J_CS_N<3>
  SA(2)  = PVPP_GHJ
  VSS(20)  = GND
  DQ(37)  = M_J_DQ<36>
  VSS(19)  = GND
  DQ(33)  = M_J_DQ<32>
  VSS(18)  = GND
  DQS4N  = M_J_DQS_DN<4>
  DQS4P  = M_J_DQS_DP<4>
  VSS(17)  = GND
  DQ(39)  = M_J_DQ<38>
  VSS(16)  = GND
  DQ(35)  = M_J_DQ<34>
  VSS(15)  = GND
  DQ(45)  = M_J_DQ<44>
  VSS(14)  = GND
  DQ(41)  = M_J_DQ<40>
  VSS(13)  = GND
  DQS5N  = M_J_DQS_DN<5>
  DQS5P  = M_J_DQS_DP<5>
  VSS(12)  = GND
  DQ(47)  = M_J_DQ<46>
  VSS(11)  = GND
  DQ(43)  = M_J_DQ<42>
  VSS(10)  = GND
  DQ(53)  = M_J_DQ<52>
  VSS(9)  = GND
  DQ(49)  = M_J_DQ<48>
  VSS(8)  = GND
  DQS6N  = M_J_DQS_DN<6>
  DQS6P  = M_J_DQS_DP<6>
  VSS(7)  = GND
  DQ(55)  = M_J_DQ<54>
  VSS(6)  = GND
  DQ(51)  = M_J_DQ<50>
  VSS(5)  = GND
  DQ(61)  = M_J_DQ<60>
  VSS(4)  = GND
  DQ(57)  = M_J_DQ<56>
  VSS(3)  = GND
  DQS7N  = M_J_DQS_DN<7>
  DQS7P  = M_J_DQS_DP<7>
  VSS(2)  = GND
  DQ(63)  = M_J_DQ<62>
  VSS(1)  = GND
  DQ(59)  = M_J_DQ<58>
  VSS(0)  = GND
  VDDSPD  = PVPP_GHJ
  SDA  = SMB_DDR_GHJ_VPP_SDA
  VPP(1)  = PVPP_GHJ
  VPP(0)  = PVPP_GHJ
  VPP(2)  = PVPP_GHJ

(kicad_pcb
	(version 20260206)
	(generator "pcbnew")
	(generator_version "10.0")
	(general
		(thickness 1.6)
		(legacy_teardrops no)
	)
	(paper "A4")
	(title_block
		(title "Wiwynn_Tioga_Pass_MB.brd")
		(comment 1 "Tioga Pass / footprint 437 of 4770 (J1G3), pads 153-202 of 291")
	)
	(layers
		(0 "F.Cu" signal "TOP")
		(4 "In1.Cu" signal "L2GND")
		(6 "In2.Cu" signal "L3")
		(8 "In3.Cu" signal "L4GND")
		(10 "In4.Cu" signal "L5")
		(12 "In5.Cu" signal "L6GND")
		(14 "In6.Cu" signal "L7VCC")
		(16 "In7.Cu" signal "L8VCC")
		(18 "In8.Cu" signal "L9GND")
		(20 "In9.Cu" signal "L10")
		(22 "In10.Cu" signal "L11GND")
		(24 "In11.Cu" signal "L12")
		(26 "In12.Cu" signal "L13GND")
		(2 "B.Cu" signal "BOTTOM")
		(9 "F.Adhes" user "F.Adhesive")
		(11 "B.Adhes" user "B.Adhesive")
		(13 "F.Paste" user "Package Geometry/Pastemask Top")
		(15 "B.Paste" user "Package Geometry/Pastemask Bottom")
		(5 "F.SilkS" user "Ref Des/Silkscreen Top")
		(7 "B.SilkS" user "Ref Des/Silkscreen Bottom")
		(1 "F.Mask" user "Board Geometry/Soldermask Top")
		(3 "B.Mask" user "Board Geometry/Soldermask Bottom")
		(17 "Dwgs.User" user "User.Drawings")
		(19 "Cmts.User" user "User.Comments")
		(21 "Eco1.User" user "User.Eco1")
		(23 "Eco2.User" user "User.Eco2")
		(25 "Edge.Cuts" user "Board Geometry/Outline")
		(27 "Margin" user)
		(31 "F.CrtYd" user "Package Geometry/Place Bound Top")
		(29 "B.CrtYd" user "Package Geometry/Place Bound Bottom")
		(35 "F.Fab" user "Ref Des/Assembly Top")
		(33 "B.Fab" user "Ref Des/Assembly Bottom")
	)
	(footprint ""
		(layer "F.Cu")
		(at 29.699458 3.778758 90)
		(property "Reference" "J1G3"
			(at 7.054088 34.562542 0)
			(unlocked yes)
			(layer "F.SilkS")
			(effects
				(font
					(size 0.7874 0.5842)
					(thickness 0.1524)
				)
				(justify left)
			)
		)
		(property "Value" ""
			(at 0 0 90)
			(layer "F.Fab")
			(effects
				(font
					(size 1.27 1.27)
				)
			)
		)
		(duplicate_pad_numbers_are_jumpers no)
		(pad "150" smd rect
			(at 4.59994 4.249928 90)
			(size 1.8034 0.508)
			(layers "F.Cu" "F.Mask" "F.Paste")
			(net "M_J_DQ<0>")
		)
		(pad "151" smd rect
			(at 4.59994 5.100066 90)
			(size 1.8034 0.508)
			(layers "F.Cu" "F.Mask" "F.Paste")
			(net "GND")
		)
		(pad "152" smd rect
			(at 4.59994 5.94995 90)
			(size 1.8034 0.508)
			(layers "F.Cu" "F.Mask" "F.Paste")
			(net "M_J_DQS_DN<0>")
		)
		(pad "153" smd rect
			(at 4.59994 6.800088 90)
			(size 1.8034 0.508)
			(layers "F.Cu" "F.Mask" "F.Paste")
			(net "M_J_DQS_DP<0>")
		)
		(pad "154" smd rect
			(at 4.59994 7.649972 90)
			(size 1.8034 0.508)
			(layers "F.Cu" "F.Mask" "F.Paste")
			(net "GND")
		)
		(pad "155" smd rect
			(at 4.59994 8.50011 90)
			(size 1.8034 0.508)
			(layers "F.Cu" "F.Mask" "F.Paste")
			(net "M_J_DQ<6>")
		)
		(pad "156" smd rect
			(at 4.59994 9.349994 90)
			(size 1.8034 0.508)
			(layers "F.Cu" "F.Mask" "F.Paste")
			(net "GND")
		)
		(pad "157" smd rect
			(at 4.59994 10.199878 90)
			(size 1.8034 0.508)
			(layers "F.Cu" "F.Mask" "F.Paste")
			(net "M_J_DQ<2>")
		)
		(pad "158" smd rect
			(at 4.59994 11.050016 90)
			(size 1.8034 0.508)
			(layers "F.Cu" "F.Mask" "F.Paste")
			(net "GND")
		)
		(pad "159" smd rect
			(at 4.59994 11.8999 90)
			(size 1.8034 0.508)
			(layers "F.Cu" "F.Mask" "F.Paste")
			(net "M_J_DQ<12>")
		)
		(pad "160" smd rect
			(at 4.59994 12.750038 90)
			(size 1.8034 0.508)
			(layers "F.Cu" "F.Mask" "F.Paste")
			(net "GND")
		)
		(pad "161" smd rect
			(at 4.59994 13.599922 90)
			(size 1.8034 0.508)
			(layers "F.Cu" "F.Mask" "F.Paste")
			(net "M_J_DQ<8>")
		)
		(pad "162" smd rect
			(at 4.59994 14.45006 90)
			(size 1.8034 0.508)
			(layers "F.Cu" "F.Mask" "F.Paste")
			(net "GND")
		)
		(pad "163" smd rect
			(at 4.59994 15.299944 90)
			(size 1.8034 0.508)
			(layers "F.Cu" "F.Mask" "F.Paste")
			(net "M_J_DQS_DN<1>")
		)
		(pad "164" smd rect
			(at 4.59994 16.150082 90)
			(size 1.8034 0.508)
			(layers "F.Cu" "F.Mask" "F.Paste")
			(net "M_J_DQS_DP<1>")
		)
		(pad "165" smd rect
			(at 4.59994 16.999966 90)
			(size 1.8034 0.508)
			(layers "F.Cu" "F.Mask" "F.Paste")
			(net "GND")
		)
		(pad "166" smd rect
			(at 4.59994 17.850104 90)
			(size 1.8034 0.508)
			(layers "F.Cu" "F.Mask" "F.Paste")
			(net "M_J_DQ<14>")
		)
		(pad "167" smd rect
			(at 4.59994 18.699988 90)
			(size 1.8034 0.508)
			(layers "F.Cu" "F.Mask" "F.Paste")
			(net "GND")
		)
		(pad "168" smd rect
			(at 4.59994 19.550126 90)
			(size 1.8034 0.508)
			(layers "F.Cu" "F.Mask" "F.Paste")
			(net "M_J_DQ<10>")
		)
		(pad "169" smd rect
			(at 4.59994 20.40001 90)
			(size 1.8034 0.508)
			(layers "F.Cu" "F.Mask" "F.Paste")
			(net "GND")
		)
		(pad "170" smd rect
			(at 4.59994 21.249894 90)
			(size 1.8034 0.508)
			(layers "F.Cu" "F.Mask" "F.Paste")
			(net "M_J_DQ<20>")
		)
		(pad "171" smd rect
			(at 4.59994 22.100032 90)
			(size 1.8034 0.508)
			(layers "F.Cu" "F.Mask" "F.Paste")
			(net "GND")
		)
		(pad "172" smd rect
			(at 4.59994 22.949916 90)
			(size 1.8034 0.508)
			(layers "F.Cu" "F.Mask" "F.Paste")
			(net "M_J_DQ<16>")
		)
		(pad "173" smd rect
			(at 4.59994 23.800054 90)
			(size 1.8034 0.508)
			(layers "F.Cu" "F.Mask" "F.Paste")
			(net "GND")
		)
		(pad "174" smd rect
			(at 4.59994 24.649938 90)
			(size 1.8034 0.508)
			(layers "F.Cu" "F.Mask" "F.Paste")
			(net "M_J_DQS_DN<2>")
		)
		(pad "175" smd rect
			(at 4.59994 25.500076 90)
			(size 1.8034 0.508)
			(layers "F.Cu" "F.Mask" "F.Paste")
			(net "M_J_DQS_DP<2>")
		)
		(pad "176" smd rect
			(at 4.59994 26.34996 90)
			(size 1.8034 0.508)
			(layers "F.Cu" "F.Mask" "F.Paste")
			(net "GND")
		)
		(pad "177" smd rect
			(at 4.59994 27.200098 90)
			(size 1.8034 0.508)
			(layers "F.Cu" "F.Mask" "F.Paste")
			(net "M_J_DQ<22>")
		)
		(pad "178" smd rect
			(at 4.59994 28.049982 90)
			(size 1.8034 0.508)
			(layers "F.Cu" "F.Mask" "F.Paste")
			(net "GND")
		)
		(pad "179" smd rect
			(at 4.59994 28.90012 90)
			(size 1.8034 0.508)
			(layers "F.Cu" "F.Mask" "F.Paste")
			(net "M_J_DQ<18>")
		)
		(pad "180" smd rect
			(at 4.59994 29.750004 90)
			(size 1.8034 0.508)
			(layers "F.Cu" "F.Mask" "F.Paste")
			(net "GND")
		)
		(pad "181" smd rect
			(at 4.59994 30.599888 90)
			(size 1.8034 0.508)
			(layers "F.Cu" "F.Mask" "F.Paste")
			(net "M_J_DQ<28>")
		)
		(pad "182" smd rect
			(at 4.59994 31.450026 90)
			(size 1.8034 0.508)
			(layers "F.Cu" "F.Mask" "F.Paste")
			(net "GND")
		)
		(pad "183" smd rect
			(at 4.59994 32.29991 90)
			(size 1.8034 0.508)
			(layers "F.Cu" "F.Mask" "F.Paste")
			(net "M_J_DQ<24>")
		)
		(pad "184" smd rect
			(at 4.59994 33.150048 90)
			(size 1.8034 0.508)
			(layers "F.Cu" "F.Mask" "F.Paste")
			(net "GND")
		)
		(pad "185" smd rect
			(at 4.59994 33.999932 90)
			(size 1.8034 0.508)
			(layers "F.Cu" "F.Mask" "F.Paste")
			(net "M_J_DQS_DN<3>")
		)
		(pad "186" smd rect
			(at 4.59994 34.85007 90)
			(size 1.8034 0.508)
			(layers "F.Cu" "F.Mask" "F.Paste")
			(net "M_J_DQS_DP<3>")
		)
		(pad "187" smd rect
			(at 4.59994 35.699954 90)
			(size 1.8034 0.508)
			(layers "F.Cu" "F.Mask" "F.Paste")
			(net "GND")
		)
		(pad "188" smd rect
			(at 4.59994 36.550092 90)
			(size 1.8034 0.508)
			(layers "F.Cu" "F.Mask" "F.Paste")
			(net "M_J_DQ<30>")
		)
		(pad "189" smd rect
			(at 4.59994 37.399976 90)
			(size 1.8034 0.508)
			(layers "F.Cu" "F.Mask" "F.Paste")
			(net "GND")
		)
		(pad "190" smd rect
			(at 4.59994 38.250114 90)
			(size 1.8034 0.508)
			(layers "F.Cu" "F.Mask" "F.Paste")
			(net "M_J_DQ<26>")
		)
		(pad "191" smd rect
			(at 4.59994 39.099998 90)
			(size 1.8034 0.508)
			(layers "F.Cu" "F.Mask" "F.Paste")
			(net "GND")
		)
		(pad "192" smd rect
			(at 4.59994 39.949882 90)
			(size 1.8034 0.508)
			(layers "F.Cu" "F.Mask" "F.Paste")
			(net "M_J_ECC<4>")
		)
		(pad "193" smd rect
			(at 4.59994 40.80002 90)
			(size 1.8034 0.508)
			(layers "F.Cu" "F.Mask" "F.Paste")
			(net "GND")
		)
		(pad "194" smd rect
			(at 4.59994 41.649904 90)
			(size 1.8034 0.508)
			(layers "F.Cu" "F.Mask" "F.Paste")
			(net "M_J_ECC<0>")
		)
		(pad "195" smd rect
			(at 4.59994 42.500042 90)
			(size 1.8034 0.508)
			(layers "F.Cu" "F.Mask" "F.Paste")
			(net "GND")
		)
		(pad "196" smd rect
			(at 4.59994 43.349926 90)
			(size 1.8034 0.508)
			(layers "F.Cu" "F.Mask" "F.Paste")
			(net "M_J_DQS_DN<8>")
		)
		(pad "197" smd rect
			(at 4.59994 44.200064 90)
			(size 1.8034 0.508)
			(layers "F.Cu" "F.Mask" "F.Paste")
			(net "M_J_DQS_DP<8>")
		)
		(pad "198" smd rect
			(at 4.59994 45.049948 90)
			(size 1.8034 0.508)
			(layers "F.Cu" "F.Mask" "F.Paste")
			(net "GND")
		)
		(pad "199" smd rect
			(at 4.59994 45.900086 90)
			(size 1.8034 0.508)
			(layers "F.Cu" "F.Mask" "F.Paste")
			(net "M_J_ECC<6>")
		)
	)
)
